# T6G (Grand Teton) — schematic netlist excerpt (pin names and nets, part order shuffled) for the footprints in the layout excerpt that follows; sources: Cadence DE-HDL packaged netlist, KiCad conversion of 04192023_DAF0TMB3IC0_F0TG_MB_C_brd_V02_OCP.brd

R4521  Q_RES  1K 1% CHIP  pkg 0402LF  page 233 : A = P3V3_AUX ; B = CLK_GEN2_BMC_RC_OE_N
TP5  TP  NA  pkg TP  page 27 : TP = VSENSE_PVDDIO_P0_DP
PC84_1  Q_CAP  0.1UF 25V 10% X7R  pkg 0402  page 201 : A = PVDDCR_CPU1_P0_VCCS ; B = GND
R726  Q_RES  4.7K 5% CHIP  pkg 0201LF  page 320 : A = JTAG_TEST_MODE_RT_CPU1_P0 ; B = GND

(kicad_pcb
	(version 20260206)
	(generator "pcbnew")
	(generator_version "10.0")
	(general
		(thickness 1.6)
		(legacy_teardrops no)
	)
	(paper "A4")
	(title_block
		(title "04192023_DAF0TMB3IC0_F0TG_MB_C_brd_V02_OCP.brd")
		(comment 1 "Grand Teton / footprints 3741-3744 of 8354")
	)
	(layers
		(0 "F.Cu" signal "TOP")
		(4 "In1.Cu" signal "GND")
		(6 "In2.Cu" signal "IN1")
		(8 "In3.Cu" signal "GND1")
		(10 "In4.Cu" signal "IN2")
		(12 "In5.Cu" signal "GND2")
		(14 "In6.Cu" signal "IN3")
		(16 "In7.Cu" signal "GND3")
		(18 "In8.Cu" signal "VCC")
		(20 "In9.Cu" signal "VCC1")
		(22 "In10.Cu" signal "GND4")
		(24 "In11.Cu" signal "IN4")
		(26 "In12.Cu" signal "GND5")
		(28 "In13.Cu" signal "IN5")
		(30 "In14.Cu" signal "GND6")
		(32 "In15.Cu" signal "IN6")
		(34 "In16.Cu" signal "GND7")
		(2 "B.Cu" signal "BOTTOM")
		(9 "F.Adhes" user "F.Adhesive")
		(11 "B.Adhes" user "B.Adhesive")
		(13 "F.Paste" user "Package Geometry/Pastemask Top")
		(15 "B.Paste" user "Package Geometry/Pastemask Bottom")
		(5 "F.SilkS" user "Ref Des/Silkscreen Top")
		(7 "B.SilkS" user "Ref Des/Silkscreen Bottom")
		(1 "F.Mask" user "Board Geometry/Soldermask Top")
		(3 "B.Mask" user "Board Geometry/Soldermask Bottom")
		(17 "Dwgs.User" user "User.Drawings")
		(19 "Cmts.User" user "User.Comments")
		(21 "Eco1.User" user "User.Eco1")
		(23 "Eco2.User" user "User.Eco2")
		(25 "Edge.Cuts" user "Board Geometry/Outline")
		(27 "Margin" user)
		(31 "F.CrtYd" user "Package Geometry/Place Bound Top")
		(29 "B.CrtYd" user "Package Geometry/Place Bound Bottom")
		(35 "F.Fab" user "Ref Des/Assembly Top")
		(33 "B.Fab" user "Ref Des/Assembly Bottom")
	)
	(footprint ""
		(layer "F.Cu")
		(at 332.365096 -339.831172 90)
		(property "Reference" "PC84_1"
			(at 0 0 90)
			(layer "F.SilkS")
			(hide yes)
			(effects
				(font
					(size 1.27 1.27)
				)
			)
		)
		(property "Value" ""
			(at 0 0 90)
			(layer "F.Fab")
			(effects
				(font
					(size 1.27 1.27)
				)
			)
		)
		(duplicate_pad_numbers_are_jumpers no)
		(fp_line
			(start 0.7874 -0.4064)
			(end 0.7874 0.4064)
			(stroke
				(width 0.1524)
				(type default)
			)
			(layer "F.SilkS")
		)
		(fp_line
			(start -0.7874 -0.4064)
			(end 0.7874 -0.4064)
			(stroke
				(width 0.1524)
				(type default)
			)
			(layer "F.SilkS")
		)
		(fp_line
			(start 0.7874 0.4064)
			(end -0.7874 0.4064)
			(stroke
				(width 0.1524)
				(type default)
			)
			(layer "F.SilkS")
		)
		(fp_line
			(start -0.7874 0.4064)
			(end -0.7874 -0.4064)
			(stroke
				(width 0.1524)
				(type default)
			)
			(layer "F.SilkS")
		)
		(fp_line
			(start -0.12065 -0.305054)
			(end -0.12065 -0.2794)
			(stroke
				(width 0.1)
				(type default)
			)
			(layer "F.Fab")
		)
		(fp_line
			(start -0.67945 -0.305054)
			(end -0.12065 -0.305054)
			(stroke
				(width 0.1)
				(type default)
			)
			(layer "F.Fab")
		)
		(fp_line
			(start 0.67945 -0.3048)
			(end 0.67945 0.3048)
			(stroke
				(width 0.1)
				(type default)
			)
			(layer "F.Fab")
		)
		(fp_line
			(start 0.12065 -0.3048)
			(end 0.67945 -0.3048)
			(stroke
				(width 0.1)
				(type default)
			)
			(layer "F.Fab")
		)
		(fp_line
			(start 0.12065 -0.2794)
			(end 0.12065 -0.3048)
			(stroke
				(width 0.1)
				(type default)
			)
			(layer "F.Fab")
		)
		(fp_line
			(start -0.12065 -0.2794)
			(end 0.12065 -0.2794)
			(stroke
				(width 0.1)
				(type default)
			)
			(layer "F.Fab")
		)
		(fp_line
			(start 0.120396 0.2794)
			(end -0.12065 0.2794)
			(stroke
				(width 0.1)
				(type default)
			)
			(layer "F.Fab")
		)
		(fp_line
			(start -0.12065 0.2794)
			(end -0.12065 0.3048)
			(stroke
				(width 0.1)
				(type default)
			)
			(layer "F.Fab")
		)
		(fp_line
			(start 0.67945 0.3048)
			(end 0.120396 0.3048)
			(stroke
				(width 0.1)
				(type default)
			)
			(layer "F.Fab")
		)
		(fp_line
			(start 0.120396 0.3048)
			(end 0.120396 0.2794)
			(stroke
				(width 0.1)
				(type default)
			)
			(layer "F.Fab")
		)
		(fp_line
			(start -0.12065 0.3048)
			(end -0.67945 0.3048)
			(stroke
				(width 0.1)
				(type default)
			)
			(layer "F.Fab")
		)
		(fp_line
			(start -0.67945 0.3048)
			(end -0.67945 -0.305054)
			(stroke
				(width 0.1)
				(type default)
			)
			(layer "F.Fab")
		)
		(pad "1" smd circle
			(at -0.40005 0 90)
			(size 0 0)
			(layers "F.Cu" "F.Mask" "F.Paste")
			(net "PVDDCR_CPU1_P0_VCCS")
		)
		(pad "2" smd circle
			(at 0.40005 0 90)
			(size 0 0)
			(layers "F.Cu" "F.Mask" "F.Paste")
			(net "GND")
		)
	)
	(footprint ""
		(layer "F.Cu")
		(at 41.5544 -391.795)
		(property "Reference" "R726"
			(at 0 0 0)
			(layer "F.SilkS")
			(hide yes)
			(effects
				(font
					(size 1.27 1.27)
				)
			)
		)
		(property "Value" ""
			(at 0 0 0)
			(layer "F.Fab")
			(effects
				(font
					(size 1.27 1.27)
				)
			)
		)
		(duplicate_pad_numbers_are_jumpers no)
		(fp_line
			(start -0.32512 -0.175006)
			(end 0.32512 -0.175006)
			(stroke
				(width 0.1)
				(type default)
			)
			(layer "F.Fab")
		)
		(fp_line
			(start -0.32512 0.175006)
			(end -0.32512 -0.175006)
			(stroke
				(width 0.1)
				(type default)
			)
			(layer "F.Fab")
		)
		(fp_line
			(start 0.32512 -0.175006)
			(end 0.32512 0.175006)
			(stroke
				(width 0.1)
				(type default)
			)
			(layer "F.Fab")
		)
		(fp_line
			(start 0.32512 0.175006)
			(end -0.32512 0.175006)
			(stroke
				(width 0.1)
				(type default)
			)
			(layer "F.Fab")
		)
		(pad "1" smd rect
			(at -0.2667 0)
			(size 0.3048 0.381)
			(layers "F.Cu" "F.Mask" "F.Paste")
			(net "JTAG_TEST_MODE_RT_CPU1_P0")
		)
		(pad "2" smd rect
			(at 0.2667 0 180)
			(size 0.3048 0.381)
			(layers "F.Cu" "F.Mask" "F.Paste")
			(net "GND")
		)
	)
	(footprint ""
		(layer "F.Cu")
		(at 16.368268 -128.51511 -90)
		(property "Reference" "R4521"
			(at 0 0 270)
			(layer "F.SilkS")
			(hide yes)
			(effects
				(font
					(size 1.27 1.27)
				)
			)
		)
		(property "Value" ""
			(at 0 0 270)
			(layer "F.Fab")
			(effects
				(font
					(size 1.27 1.27)
				)
			)
		)
		(duplicate_pad_numbers_are_jumpers no)
		(fp_line
			(start -0.7874 0.4064)
			(end -0.7874 -0.4064)
			(stroke
				(width 0.1524)
				(type default)
			)
			(layer "F.SilkS")
		)
		(fp_line
			(start 0.7874 0.4064)
			(end -0.7874 0.4064)
			(stroke
				(width 0.1524)
				(type default)
			)
			(layer "F.SilkS")
		)
		(fp_line
			(start -0.7874 -0.4064)
			(end 0.7874 -0.4064)
			(stroke
				(width 0.1524)
				(type default)
			)
			(layer "F.SilkS")
		)
		(fp_line
			(start 0.7874 -0.4064)
			(end 0.7874 0.4064)
			(stroke
				(width 0.1524)
				(type default)
			)
			(layer "F.SilkS")
		)
		(fp_line
			(start -0.67945 0.3048)
			(end -0.67945 -0.305054)
			(stroke
				(width 0.1)
				(type default)
			)
			(layer "F.Fab")
		)
		(fp_line
			(start -0.12065 0.3048)
			(end -0.67945 0.3048)
			(stroke
				(width 0.1)
				(type default)
			)
			(layer "F.Fab")
		)
		(fp_line
			(start 0.120396 0.3048)
			(end 0.120396 0.2794)
			(stroke
				(width 0.1)
				(type default)
			)
			(layer "F.Fab")
		)
		(fp_line
			(start 0.67945 0.3048)
			(end 0.120396 0.3048)
			(stroke
				(width 0.1)
				(type default)
			)
			(layer "F.Fab")
		)
		(fp_line
			(start -0.12065 0.2794)
			(end -0.12065 0.3048)
			(stroke
				(width 0.1)
				(type default)
			)
			(layer "F.Fab")
		)
		(fp_line
			(start 0.120396 0.2794)
			(end -0.12065 0.2794)
			(stroke
				(width 0.1)
				(type default)
			)
			(layer "F.Fab")
		)
		(fp_line
			(start -0.12065 -0.2794)
			(end 0.12065 -0.2794)
			(stroke
				(width 0.1)
				(type default)
			)
			(layer "F.Fab")
		)
		(fp_line
			(start 0.12065 -0.2794)
			(end 0.12065 -0.3048)
			(stroke
				(width 0.1)
				(type default)
			)
			(layer "F.Fab")
		)
		(fp_line
			(start 0.12065 -0.3048)
			(end 0.67945 -0.3048)
			(stroke
				(width 0.1)
				(type default)
			)
			(layer "F.Fab")
		)
		(fp_line
			(start 0.67945 -0.3048)
			(end 0.67945 0.3048)
			(stroke
				(width 0.1)
				(type default)
			)
			(layer "F.Fab")
		)
		(fp_line
			(start -0.67945 -0.305054)
			(end -0.12065 -0.305054)
			(stroke
				(width 0.1)
				(type default)
			)
			(layer "F.Fab")
		)
		(fp_line
			(start -0.12065 -0.305054)
			(end -0.12065 -0.2794)
			(stroke
				(width 0.1)
				(type default)
			)
			(layer "F.Fab")
		)
		(pad "1" smd circle
			(at -0.40005 0 270)
			(size 0 0)
			(layers "F.Cu" "F.Mask" "F.Paste")
			(net "P3V3_AUX")
		)
		(pad "2" smd circle
			(at 0.40005 0 270)
			(size 0 0)
			(layers "F.Cu" "F.Mask" "F.Paste")
			(net "CLK_GEN2_BMC_RC_OE_N")
		)
	)
	(footprint ""
		(layer "F.Cu")
		(at 266.862306 -332.015846)
		(property "Reference" "TP5"
			(at -5.423916 0.05207 0)
			(unlocked yes)
			(layer "F.SilkS")
			(effects
				(font
					(size 0.7874 0.5842)
					(thickness 0.1524)
				)
				(justify left)
			)
		)
		(property "Value" ""
			(at 0 0 0)
			(layer "F.Fab")
			(effects
				(font
					(size 1.27 1.27)
				)
			)
		)
		(duplicate_pad_numbers_are_jumpers no)
		(pad "1" smd circle
			(at 0 0)
			(size 0.762 0.762)
			(layers "F.Cu" "F.Mask" "F.Paste")
			(net "VSENSE_PVDDIO_P0_DP")
		)
	)
)
